# S9S_MB_2U (Grand Teton) — schematic netlist excerpt (pin names and nets, part order shuffled) for the footprints in the layout excerpt that follows; sources: Cadence DE-HDL packaged netlist, KiCad conversion of 03242023_DA0F0TMBIJ0_F0T_Motherboard_J_brd_V01_OCP.brd

R4604  Q_RES  4.7K 5% CHIP  pkg 0402LF  page 224 : A = P3V3_AUX ; B = PWRGD_PS_PWROK_PLD_N
C964  Q_CAP_DIFFBUS  DIFF BUS_0.22UF 6.3V 20% X6S  pkg C0201  page 173 : \1\ = P5E_CPU0_PE2_TX_C_DN<0> ; \2\ = P5E_CPU0_PE2_TX_DN<0>
R3046  Q_RES  0 5% CHIP  pkg 0402LF  page 215 : A = FM_UV_ADR_TRIGGER_N ; B = FM_UV_ADR_TRIGGER_R_N

(kicad_pcb
	(version 20260206)
	(generator "pcbnew")
	(generator_version "10.0")
	(general
		(thickness 1.6)
		(legacy_teardrops no)
	)
	(paper "A4")
	(title_block
		(title "03242023_DA0F0TMBIJ0_F0T_Motherboard_J_brd_V01_OCP.brd")
		(comment 1 "Grand Teton / footprints 3226-3228 of 6105")
	)
	(layers
		(0 "F.Cu" signal "TOP")
		(4 "In1.Cu" signal "GND")
		(6 "In2.Cu" signal "IN1")
		(8 "In3.Cu" signal "GND1")
		(10 "In4.Cu" signal "IN2")
		(12 "In5.Cu" signal "GND2")
		(14 "In6.Cu" signal "IN3")
		(16 "In7.Cu" signal "GND3")
		(18 "In8.Cu" signal "VCC")
		(20 "In9.Cu" signal "VCC1")
		(22 "In10.Cu" signal "GND4")
		(24 "In11.Cu" signal "IN4")
		(26 "In12.Cu" signal "GND5")
		(28 "In13.Cu" signal "IN5")
		(30 "In14.Cu" signal "GND6")
		(32 "In15.Cu" signal "IN6")
		(34 "In16.Cu" signal "GND7")
		(2 "B.Cu" signal "BOTTOM")
		(9 "F.Adhes" user "F.Adhesive")
		(11 "B.Adhes" user "B.Adhesive")
		(13 "F.Paste" user "Package Geometry/Pastemask Top")
		(15 "B.Paste" user "Package Geometry/Pastemask Bottom")
		(5 "F.SilkS" user "Ref Des/Silkscreen Top")
		(7 "B.SilkS" user "Ref Des/Silkscreen Bottom")
		(1 "F.Mask" user "Board Geometry/Soldermask Top")
		(3 "B.Mask" user "Board Geometry/Soldermask Bottom")
		(17 "Dwgs.User" user "User.Drawings")
		(19 "Cmts.User" user "User.Comments")
		(21 "Eco1.User" user "User.Eco1")
		(23 "Eco2.User" user "User.Eco2")
		(25 "Edge.Cuts" user "Board Geometry/Outline")
		(27 "Margin" user)
		(31 "F.CrtYd" user "Package Geometry/Place Bound Top")
		(29 "B.CrtYd" user "Package Geometry/Place Bound Bottom")
		(35 "F.Fab" user "Ref Des/Assembly Top")
		(33 "B.Fab" user "Ref Des/Assembly Bottom")
	)
	(footprint ""
		(layer "F.Cu")
		(at 147.447 -130.647948)
		(property "Reference" "R4604"
			(at 0 0 0)
			(layer "F.SilkS")
			(hide yes)
			(effects
				(font
					(size 1.27 1.27)
				)
			)
		)
		(property "Value" ""
			(at 0 0 0)
			(layer "F.Fab")
			(effects
				(font
					(size 1.27 1.27)
				)
			)
		)
		(duplicate_pad_numbers_are_jumpers no)
		(fp_line
			(start -0.7874 -0.4064)
			(end 0.7874 -0.4064)
			(stroke
				(width 0.1524)
				(type default)
			)
			(layer "F.SilkS")
		)
		(fp_line
			(start -0.7874 0.4064)
			(end -0.7874 -0.4064)
			(stroke
				(width 0.1524)
				(type default)
			)
			(layer "F.SilkS")
		)
		(fp_line
			(start 0.7874 -0.4064)
			(end 0.7874 0.4064)
			(stroke
				(width 0.1524)
				(type default)
			)
			(layer "F.SilkS")
		)
		(fp_line
			(start 0.7874 0.4064)
			(end -0.7874 0.4064)
			(stroke
				(width 0.1524)
				(type default)
			)
			(layer "F.SilkS")
		)
		(fp_line
			(start -0.67945 -0.305054)
			(end -0.12065 -0.305054)
			(stroke
				(width 0.1)
				(type default)
			)
			(layer "F.Fab")
		)
		(fp_line
			(start -0.67945 0.3048)
			(end -0.67945 -0.305054)
			(stroke
				(width 0.1)
				(type default)
			)
			(layer "F.Fab")
		)
		(fp_line
			(start -0.12065 -0.305054)
			(end -0.12065 -0.2794)
			(stroke
				(width 0.1)
				(type default)
			)
			(layer "F.Fab")
		)
		(fp_line
			(start -0.12065 -0.2794)
			(end 0.12065 -0.2794)
			(stroke
				(width 0.1)
				(type default)
			)
			(layer "F.Fab")
		)
		(fp_line
			(start -0.12065 0.2794)
			(end -0.12065 0.3048)
			(stroke
				(width 0.1)
				(type default)
			)
			(layer "F.Fab")
		)
		(fp_line
			(start -0.12065 0.3048)
			(end -0.67945 0.3048)
			(stroke
				(width 0.1)
				(type default)
			)
			(layer "F.Fab")
		)
		(fp_line
			(start 0.120396 0.2794)
			(end -0.12065 0.2794)
			(stroke
				(width 0.1)
				(type default)
			)
			(layer "F.Fab")
		)
		(fp_line
			(start 0.120396 0.3048)
			(end 0.120396 0.2794)
			(stroke
				(width 0.1)
				(type default)
			)
			(layer "F.Fab")
		)
		(fp_line
			(start 0.12065 -0.3048)
			(end 0.67945 -0.3048)
			(stroke
				(width 0.1)
				(type default)
			)
			(layer "F.Fab")
		)
		(fp_line
			(start 0.12065 -0.2794)
			(end 0.12065 -0.3048)
			(stroke
				(width 0.1)
				(type default)
			)
			(layer "F.Fab")
		)
		(fp_line
			(start 0.67945 -0.3048)
			(end 0.67945 0.3048)
			(stroke
				(width 0.1)
				(type default)
			)
			(layer "F.Fab")
		)
		(fp_line
			(start 0.67945 0.3048)
			(end 0.120396 0.3048)
			(stroke
				(width 0.1)
				(type default)
			)
			(layer "F.Fab")
		)
		(pad "1" smd circle
			(at -0.40005 0)
			(size 0 0)
			(layers "F.Cu" "F.Mask" "F.Paste")
			(net "P3V3_AUX")
		)
		(pad "2" smd circle
			(at 0.40005 0)
			(size 0 0)
			(layers "F.Cu" "F.Mask" "F.Paste")
			(net "PWRGD_PS_PWROK_PLD_N")
		)
	)
	(footprint ""
		(layer "F.Cu")
		(at 418.26053 -402.371052 -90)
		(property "Reference" "C964"
			(at 0 0 270)
			(layer "F.SilkS")
			(hide yes)
			(effects
				(font
					(size 1.27 1.27)
				)
			)
		)
		(property "Value" ""
			(at 0 0 270)
			(layer "F.Fab")
			(effects
				(font
					(size 1.27 1.27)
				)
			)
		)
		(duplicate_pad_numbers_are_jumpers no)
		(fp_line
			(start -0.299974 0.150114)
			(end -0.299974 -0.150114)
			(stroke
				(width 0.1)
				(type default)
			)
			(layer "F.Fab")
		)
		(fp_line
			(start 0.299974 0.150114)
			(end -0.299974 0.150114)
			(stroke
				(width 0.1)
				(type default)
			)
			(layer "F.Fab")
		)
		(fp_line
			(start -0.299974 -0.150114)
			(end 0.299974 -0.150114)
			(stroke
				(width 0.1)
				(type default)
			)
			(layer "F.Fab")
		)
		(fp_line
			(start 0.299974 -0.150114)
			(end 0.299974 0.150114)
			(stroke
				(width 0.1)
				(type default)
			)
			(layer "F.Fab")
		)
		(pad "1" smd rect
			(at -0.2667 0 270)
			(size 0.3048 0.381)
			(layers "F.Cu" "F.Mask" "F.Paste")
			(net "P5E_CPU0_PE2_TX_C_DN<0>")
		)
		(pad "2" smd rect
			(at 0.2667 0 270)
			(size 0.3048 0.381)
			(layers "F.Cu" "F.Mask" "F.Paste")
			(net "P5E_CPU0_PE2_TX_DN<0>")
		)
	)
	(footprint ""
		(layer "F.Cu")
		(at 193.60388 -101.145848 180)
		(property "Reference" "R3046"
			(at 0 0 180)
			(layer "F.SilkS")
			(hide yes)
			(effects
				(font
					(size 1.27 1.27)
				)
			)
		)
		(property "Value" ""
			(at 0 0 180)
			(layer "F.Fab")
			(effects
				(font
					(size 1.27 1.27)
				)
			)
		)
		(duplicate_pad_numbers_are_jumpers no)
		(fp_line
			(start 0.7874 0.4064)
			(end -0.7874 0.4064)
			(stroke
				(width 0.1524)
				(type default)
			)
			(layer "F.SilkS")
		)
		(fp_line
			(start 0.7874 -0.4064)
			(end 0.7874 0.4064)
			(stroke
				(width 0.1524)
				(type default)
			)
			(layer "F.SilkS")
		)
		(fp_line
			(start -0.7874 0.4064)
			(end -0.7874 -0.4064)
			(stroke
				(width 0.1524)
				(type default)
			)
			(layer "F.SilkS")
		)
		(fp_line
			(start -0.7874 -0.4064)
			(end 0.7874 -0.4064)
			(stroke
				(width 0.1524)
				(type default)
			)
			(layer "F.SilkS")
		)
		(fp_line
			(start 0.67945 0.3048)
			(end 0.120396 0.3048)
			(stroke
				(width 0.1)
				(type default)
			)
			(layer "F.Fab")
		)
		(fp_line
			(start 0.67945 -0.3048)
			(end 0.67945 0.3048)
			(stroke
				(width 0.1)
				(type default)
			)
			(layer "F.Fab")
		)
		(fp_line
			(start 0.12065 -0.2794)
			(end 0.12065 -0.3048)
			(stroke
				(width 0.1)
				(type default)
			)
			(layer "F.Fab")
		)
		(fp_line
			(start 0.12065 -0.3048)
			(end 0.67945 -0.3048)
			(stroke
				(width 0.1)
				(type default)
			)
			(layer "F.Fab")
		)
		(fp_line
			(start 0.120396 0.3048)
			(end 0.120396 0.2794)
			(stroke
				(width 0.1)
				(type default)
			)
			(layer "F.Fab")
		)
		(fp_line
			(start 0.120396 0.2794)
			(end -0.12065 0.2794)
			(stroke
				(width 0.1)
				(type default)
			)
			(layer "F.Fab")
		)
		(fp_line
			(start -0.12065 0.3048)
			(end -0.67945 0.3048)
			(stroke
				(width 0.1)
				(type default)
			)
			(layer "F.Fab")
		)
		(fp_line
			(start -0.12065 0.2794)
			(end -0.12065 0.3048)
			(stroke
				(width 0.1)
				(type default)
			)
			(layer "F.Fab")
		)
		(fp_line
			(start -0.12065 -0.2794)
			(end 0.12065 -0.2794)
			(stroke
				(width 0.1)
				(type default)
			)
			(layer "F.Fab")
		)
		(fp_line
			(start -0.12065 -0.305054)
			(end -0.12065 -0.2794)
			(stroke
				(width 0.1)
				(type default)
			)
			(layer "F.Fab")
		)
		(fp_line
			(start -0.67945 0.3048)
			(end -0.67945 -0.305054)
			(stroke
				(width 0.1)
				(type default)
			)
			(layer "F.Fab")
		)
		(fp_line
			(start -0.67945 -0.305054)
			(end -0.12065 -0.305054)
			(stroke
				(width 0.1)
				(type default)
			)
			(layer "F.Fab")
		)
		(pad "1" smd circle
			(at -0.40005 0 180)
			(size 0 0)
			(layers "F.Cu" "F.Mask" "F.Paste")
			(net "FM_UV_ADR_TRIGGER_N")
		)
		(pad "2" smd circle
			(at 0.40005 0 180)
			(size 0 0)
			(layers "F.Cu" "F.Mask" "F.Paste")
			(net "FM_UV_ADR_TRIGGER_R_N")
		)
	)
)
